# BASEBOARD_FAB2 (Tioga Pass) — schematic netlist excerpt (pin names and nets, part order shuffled) for the footprints in the layout excerpt that follows; sources: Cadence DE-HDL packaged netlist, KiCad conversion of Wiwynn_Tioga_Pass_MB.brd

R2M7  RES  33.2 1% CHIP  pkg 0402  page 119 : A = FM_ADR_MODE_SEL_R ; B = FM_ADR_MODE_SEL
C7G6  CAP  0.22UF 16V 10% X7R  pkg 0402  page 105 : A = P3E_CPU0_PE2_SS_TXN<15> ; B = P3E_CPU0_PE2_SS_C_TXN<15>
R3D3  RES  100.0 1% CHIP  pkg 0402  page 55 : A = A_CPU1_KLM_RCOMP2 ; B = GND

(kicad_pcb
	(version 20260206)
	(generator "pcbnew")
	(generator_version "10.0")
	(general
		(thickness 1.6)
		(legacy_teardrops no)
	)
	(paper "A4")
	(title_block
		(title "Wiwynn_Tioga_Pass_MB.brd")
		(comment 1 "Tioga Pass / footprints 1242-1244 of 4770")
	)
	(layers
		(0 "F.Cu" signal "TOP")
		(4 "In1.Cu" signal "L2GND")
		(6 "In2.Cu" signal "L3")
		(8 "In3.Cu" signal "L4GND")
		(10 "In4.Cu" signal "L5")
		(12 "In5.Cu" signal "L6GND")
		(14 "In6.Cu" signal "L7VCC")
		(16 "In7.Cu" signal "L8VCC")
		(18 "In8.Cu" signal "L9GND")
		(20 "In9.Cu" signal "L10")
		(22 "In10.Cu" signal "L11GND")
		(24 "In11.Cu" signal "L12")
		(26 "In12.Cu" signal "L13GND")
		(2 "B.Cu" signal "BOTTOM")
		(9 "F.Adhes" user "F.Adhesive")
		(11 "B.Adhes" user "B.Adhesive")
		(13 "F.Paste" user "Package Geometry/Pastemask Top")
		(15 "B.Paste" user "Package Geometry/Pastemask Bottom")
		(5 "F.SilkS" user "Ref Des/Silkscreen Top")
		(7 "B.SilkS" user "Ref Des/Silkscreen Bottom")
		(1 "F.Mask" user "Board Geometry/Soldermask Top")
		(3 "B.Mask" user "Board Geometry/Soldermask Bottom")
		(17 "Dwgs.User" user "User.Drawings")
		(19 "Cmts.User" user "User.Comments")
		(21 "Eco1.User" user "User.Eco1")
		(23 "Eco2.User" user "User.Eco2")
		(25 "Edge.Cuts" user "Board Geometry/Outline")
		(27 "Margin" user)
		(31 "F.CrtYd" user "Package Geometry/Place Bound Top")
		(29 "B.CrtYd" user "Package Geometry/Place Bound Bottom")
		(35 "F.Fab" user "Ref Des/Assembly Top")
		(33 "B.Fab" user "Ref Des/Assembly Bottom")
	)
	(footprint ""
		(layer "F.Cu")
		(at 363.165644 -10.916158)
		(property "Reference" "C7G6"
			(at 0 0 0)
			(layer "F.SilkS")
			(hide yes)
			(effects
				(font
					(size 1.27 1.27)
				)
			)
		)
		(property "Value" ""
			(at 0 0 0)
			(layer "F.Fab")
			(effects
				(font
					(size 1.27 1.27)
				)
			)
		)
		(duplicate_pad_numbers_are_jumpers no)
		(fp_rect
			(start -0.3048 0.9906)
			(end 0.3048 -0.1016)
			(stroke
				(width 0)
				(type default)
			)
			(fill no)
			(layer "F.CrtYd")
		)
		(fp_line
			(start -0.3048 -0.1016)
			(end -0.3048 0.9906)
			(stroke
				(width 0.1)
				(type default)
			)
			(layer "F.Fab")
		)
		(fp_line
			(start -0.3048 0.9906)
			(end 0.3048 0.9906)
			(stroke
				(width 0.1)
				(type default)
			)
			(layer "F.Fab")
		)
		(fp_line
			(start 0.3048 -0.1016)
			(end -0.3048 -0.1016)
			(stroke
				(width 0.1)
				(type default)
			)
			(layer "F.Fab")
		)
		(fp_line
			(start 0.3048 0.9906)
			(end 0.3048 -0.1016)
			(stroke
				(width 0.1)
				(type default)
			)
			(layer "F.Fab")
		)
		(pad "1" smd rect
			(at 0 0)
			(size 0.508 0.508)
			(layers "F.Cu" "F.Mask" "F.Paste")
			(net "P3E_CPU0_PE2_SS_TXN<15>")
		)
		(pad "2" smd rect
			(at 0 0.889)
			(size 0.508 0.508)
			(layers "F.Cu" "F.Mask" "F.Paste")
			(net "P3E_CPU0_PE2_SS_C_TXN<15>")
		)
		(zone
			(layer "F.Cu")
			(hatch none 0.5)
			(connect_pads
				(clearance 0)
			)
			(min_thickness 0.25)
			(keepout
				(tracks not_allowed)
				(vias allowed)
				(pads allowed)
				(copperpour not_allowed)
				(footprints allowed)
			)
			(placement
				(enabled no)
				(sheetname "")
			)
			(fill
				(thermal_gap 0.5)
				(thermal_bridge_width 0.5)
				(island_removal_mode 0)
			)
			(polygon
				(pts
					(xy 362.911644 -10.281158) (xy 363.419644 -10.281158) (xy 363.419644 -10.662158) (xy 362.911644 -10.662158)
				)
			)
		)
		(zone
			(layer "F.Cu")
			(hatch none 0.5)
			(connect_pads
				(clearance 0)
			)
			(min_thickness 0.25)
			(keepout
				(tracks allowed)
				(vias not_allowed)
				(pads allowed)
				(copperpour not_allowed)
				(footprints allowed)
			)
			(placement
				(enabled no)
				(sheetname "")
			)
			(fill
				(thermal_gap 0.5)
				(thermal_bridge_width 0.5)
				(island_removal_mode 0)
			)
			(polygon
				(pts
					(xy 362.911644 -10.281158) (xy 363.419644 -10.281158) (xy 363.419644 -10.662158) (xy 362.911644 -10.662158)
				)
			)
		)
	)
	(footprint ""
		(layer "F.Cu")
		(at 407.8605 -114.554 90)
		(property "Reference" "R2M7"
			(at 0 0 90)
			(layer "F.SilkS")
			(hide yes)
			(effects
				(font
					(size 1.27 1.27)
				)
			)
		)
		(property "Value" ""
			(at 0 0 90)
			(layer "F.Fab")
			(effects
				(font
					(size 1.27 1.27)
				)
			)
		)
		(duplicate_pad_numbers_are_jumpers no)
		(fp_poly
			(pts
				(xy -0.2794 -0.1016) (xy 0.2794 -0.1016) (xy 0.2794 0.9906) (xy -0.2794 0.9906)
			)
			(stroke
				(width 0)
				(type default)
			)
			(fill no)
			(layer "F.CrtYd")
		)
		(fp_line
			(start 0.2794 -0.1016)
			(end -0.2794 -0.1016)
			(stroke
				(width 0.1)
				(type default)
			)
			(layer "F.Fab")
		)
		(fp_line
			(start -0.2794 -0.1016)
			(end -0.2794 0.9906)
			(stroke
				(width 0.1)
				(type default)
			)
			(layer "F.Fab")
		)
		(fp_line
			(start 0.2794 0.9906)
			(end 0.2794 -0.1016)
			(stroke
				(width 0.1)
				(type default)
			)
			(layer "F.Fab")
		)
		(fp_line
			(start -0.2794 0.9906)
			(end 0.2794 0.9906)
			(stroke
				(width 0.1)
				(type default)
			)
			(layer "F.Fab")
		)
		(pad "1" smd rect
			(at 0 0 90)
			(size 0.508 0.508)
			(layers "F.Cu" "F.Mask" "F.Paste")
			(net "FM_ADR_MODE_SEL_R")
		)
		(pad "2" smd rect
			(at 0 0.889 90)
			(size 0.508 0.508)
			(layers "F.Cu" "F.Mask" "F.Paste")
			(net "FM_ADR_MODE_SEL")
		)
		(zone
			(layer "F.Cu")
			(hatch none 0.5)
			(connect_pads
				(clearance 0)
			)
			(min_thickness 0.25)
			(keepout
				(tracks allowed)
				(vias not_allowed)
				(pads allowed)
				(copperpour not_allowed)
				(footprints allowed)
			)
			(placement
				(enabled no)
				(sheetname "")
			)
			(fill
				(thermal_gap 0.5)
				(thermal_bridge_width 0.5)
				(island_removal_mode 0)
			)
			(polygon
				(pts
					(xy 408.1145 -114.3) (xy 408.1145 -114.808) (xy 408.4955 -114.808) (xy 408.4955 -114.3)
				)
			)
		)
		(zone
			(layer "F.Cu")
			(hatch none 0.5)
			(connect_pads
				(clearance 0)
			)
			(min_thickness 0.25)
			(keepout
				(tracks not_allowed)
				(vias allowed)
				(pads allowed)
				(copperpour not_allowed)
				(footprints allowed)
			)
			(placement
				(enabled no)
				(sheetname "")
			)
			(fill
				(thermal_gap 0.5)
				(thermal_bridge_width 0.5)
				(island_removal_mode 0)
			)
			(polygon
				(pts
					(xy 408.4955 -114.3) (xy 408.4955 -114.808) (xy 408.1145 -114.808) (xy 408.1145 -114.3)
				)
			)
		)
	)
	(footprint ""
		(layer "F.Cu")
		(at 111.5314 -83.8962)
		(property "Reference" "R3D3"
			(at 0 0 0)
			(layer "F.SilkS")
			(hide yes)
			(effects
				(font
					(size 1.27 1.27)
				)
			)
		)
		(property "Value" ""
			(at 0 0 0)
			(layer "F.Fab")
			(effects
				(font
					(size 1.27 1.27)
				)
			)
		)
		(duplicate_pad_numbers_are_jumpers no)
		(fp_poly
			(pts
				(xy -0.2794 -0.1016) (xy 0.2794 -0.1016) (xy 0.2794 0.9906) (xy -0.2794 0.9906)
			)
			(stroke
				(width 0)
				(type default)
			)
			(fill no)
			(layer "F.CrtYd")
		)
		(fp_line
			(start -0.2794 -0.1016)
			(end -0.2794 0.9906)
			(stroke
				(width 0.1)
				(type default)
			)
			(layer "F.Fab")
		)
		(fp_line
			(start -0.2794 0.9906)
			(end 0.2794 0.9906)
			(stroke
				(width 0.1)
				(type default)
			)
			(layer "F.Fab")
		)
		(fp_line
			(start 0.2794 -0.1016)
			(end -0.2794 -0.1016)
			(stroke
				(width 0.1)
				(type default)
			)
			(layer "F.Fab")
		)
		(fp_line
			(start 0.2794 0.9906)
			(end 0.2794 -0.1016)
			(stroke
				(width 0.1)
				(type default)
			)
			(layer "F.Fab")
		)
		(pad "1" smd rect
			(at 0 0)
			(size 0.508 0.508)
			(layers "F.Cu" "F.Mask" "F.Paste")
			(net "A_CPU1_KLM_RCOMP2")
		)
		(pad "2" smd rect
			(at 0 0.889)
			(size 0.508 0.508)
			(layers "F.Cu" "F.Mask" "F.Paste")
			(net "GND")
		)
		(zone
			(layer "F.Cu")
			(hatch none 0.5)
			(connect_pads
				(clearance 0)
			)
			(min_thickness 0.25)
			(keepout
				(tracks allowed)
				(vias not_allowed)
				(pads allowed)
				(copperpour not_allowed)
				(footprints allowed)
			)
			(placement
				(enabled no)
				(sheetname "")
			)
			(fill
				(thermal_gap 0.5)
				(thermal_bridge_width 0.5)
				(island_removal_mode 0)
			)
			(polygon
				(pts
					(xy 111.2774 -83.6422) (xy 111.7854 -83.6422) (xy 111.7854 -83.2612) (xy 111.2774 -83.2612)
				)
			)
		)
		(zone
			(layer "F.Cu")
			(hatch none 0.5)
			(connect_pads
				(clearance 0)
			)
			(min_thickness 0.25)
			(keepout
				(tracks not_allowed)
				(vias allowed)
				(pads allowed)
				(copperpour not_allowed)
				(footprints allowed)
			)
			(placement
				(enabled no)
				(sheetname "")
			)
			(fill
				(thermal_gap 0.5)
				(thermal_bridge_width 0.5)
				(island_removal_mode 0)
			)
			(polygon
				(pts
					(xy 111.2774 -83.2612) (xy 111.7854 -83.2612) (xy 111.7854 -83.6422) (xy 111.2774 -83.6422)
				)
			)
		)
	)
)
